# T6G (Grand Teton) — schematic netlist excerpt (pin names and nets, part order shuffled) for the footprints in the layout excerpt that follows; sources: Cadence DE-HDL packaged netlist, KiCad conversion of 04192023_DAF0TMB3IC0_F0TG_MB_C_brd_V02_OCP.brd

C7028  Q_CAP  100UF 4V 20% X6S  pkg C0805  page 345 : A = P0V9_CPU1_RT2_2A ; B = GND
PC6814  Q_CAPP  470UF 2.5V 20% SPCAP  pkg SMLF  page 365 : A = P0V9_CPU1_RT_2D ; B = GND

(kicad_pcb
	(version 20260206)
	(generator "pcbnew")
	(generator_version "10.0")
	(general
		(thickness 1.6)
		(legacy_teardrops no)
	)
	(paper "A4")
	(title_block
		(title "04192023_DAF0TMB3IC0_F0TG_MB_C_brd_V02_OCP.brd")
		(comment 1 "Grand Teton / footprints 5762-5763 of 8354")
	)
	(layers
		(0 "F.Cu" signal "TOP")
		(4 "In1.Cu" signal "GND")
		(6 "In2.Cu" signal "IN1")
		(8 "In3.Cu" signal "GND1")
		(10 "In4.Cu" signal "IN2")
		(12 "In5.Cu" signal "GND2")
		(14 "In6.Cu" signal "IN3")
		(16 "In7.Cu" signal "GND3")
		(18 "In8.Cu" signal "VCC")
		(20 "In9.Cu" signal "VCC1")
		(22 "In10.Cu" signal "GND4")
		(24 "In11.Cu" signal "IN4")
		(26 "In12.Cu" signal "GND5")
		(28 "In13.Cu" signal "IN5")
		(30 "In14.Cu" signal "GND6")
		(32 "In15.Cu" signal "IN6")
		(34 "In16.Cu" signal "GND7")
		(2 "B.Cu" signal "BOTTOM")
		(9 "F.Adhes" user "F.Adhesive")
		(11 "B.Adhes" user "B.Adhesive")
		(13 "F.Paste" user "Package Geometry/Pastemask Top")
		(15 "B.Paste" user "Package Geometry/Pastemask Bottom")
		(5 "F.SilkS" user "Ref Des/Silkscreen Top")
		(7 "B.SilkS" user "Ref Des/Silkscreen Bottom")
		(1 "F.Mask" user "Board Geometry/Soldermask Top")
		(3 "B.Mask" user "Board Geometry/Soldermask Bottom")
		(17 "Dwgs.User" user "User.Drawings")
		(19 "Cmts.User" user "User.Comments")
		(21 "Eco1.User" user "User.Eco1")
		(23 "Eco2.User" user "User.Eco2")
		(25 "Edge.Cuts" user "Board Geometry/Outline")
		(27 "Margin" user)
		(31 "F.CrtYd" user "Package Geometry/Place Bound Top")
		(29 "B.CrtYd" user "Package Geometry/Place Bound Bottom")
		(35 "F.Fab" user "Ref Des/Assembly Top")
		(33 "B.Fab" user "Ref Des/Assembly Bottom")
	)
	(footprint ""
		(layer "B.Cu")
		(at 24.404574 -373.339614 90)
		(property "Reference" "PC6814"
			(at -3.896614 2.873756 270)
			(unlocked yes)
			(layer "B.SilkS")
			(effects
				(font
					(size 0.7874 0.5842)
					(thickness 0.1524)
				)
				(justify left mirror)
			)
		)
		(property "Value" ""
			(at 0 0 90)
			(layer "B.Fab")
			(effects
				(font
					(size 1.27 1.27)
				)
				(justify mirror)
			)
		)
		(duplicate_pad_numbers_are_jumpers no)
		(fp_line
			(start 4.84378 -2.150618)
			(end 4.53898 -2.150618)
			(stroke
				(width 0.1524)
				(type default)
			)
			(layer "B.SilkS")
		)
		(fp_line
			(start 4.84378 -2.150618)
			(end 4.842256 2.163064)
			(stroke
				(width 0.1524)
				(type default)
			)
			(layer "B.SilkS")
		)
		(fp_line
			(start 4.69138 -2.150618)
			(end 4.692396 2.161032)
			(stroke
				(width 0.1524)
				(type default)
			)
			(layer "B.SilkS")
		)
		(fp_line
			(start 4.53898 -2.150618)
			(end 4.539742 2.152142)
			(stroke
				(width 0.1524)
				(type default)
			)
			(layer "B.SilkS")
		)
		(fp_line
			(start 4.53898 -2.15011)
			(end -3.871214 -2.15011)
			(stroke
				(width 0.1524)
				(type default)
			)
			(layer "B.SilkS")
		)
		(fp_line
			(start -4.53898 -1.849374)
			(end -4.53898 2.15011)
			(stroke
				(width 0.1524)
				(type default)
			)
			(layer "B.SilkS")
		)
		(fp_line
			(start 4.53898 2.15011)
			(end 4.53898 -2.15011)
			(stroke
				(width 0.1524)
				(type default)
			)
			(layer "B.SilkS")
		)
		(fp_line
			(start -4.53898 2.15011)
			(end 4.53898 2.15011)
			(stroke
				(width 0.1524)
				(type default)
			)
			(layer "B.SilkS")
		)
		(fp_line
			(start 4.83108 2.150364)
			(end 4.447794 2.149348)
			(stroke
				(width 0.1524)
				(type default)
			)
			(layer "B.SilkS")
		)
		(fp_line
			(start 3.64998 -2.15011)
			(end -3.64998 -2.15011)
			(stroke
				(width 0.1)
				(type default)
			)
			(layer "B.Fab")
		)
		(fp_line
			(start -3.64998 -2.15011)
			(end -3.64998 2.15011)
			(stroke
				(width 0.1)
				(type default)
			)
			(layer "B.Fab")
		)
		(fp_line
			(start 3.64998 2.15011)
			(end 3.64998 -2.15011)
			(stroke
				(width 0.1)
				(type default)
			)
			(layer "B.Fab")
		)
		(fp_line
			(start -3.64998 2.15011)
			(end 3.64998 2.15011)
			(stroke
				(width 0.1)
				(type default)
			)
			(layer "B.Fab")
		)
		(fp_text user "-"
			(at -4.313174 -0.094488 90)
			(unlocked yes)
			(layer "B.SilkS")
			(effects
				(font
					(size 1.905 1.4224)
					(thickness 0.1524)
				)
				(justify left mirror)
			)
		)
		(fp_text user "+"
			(at 6.839712 1.525778 90)
			(unlocked yes)
			(layer "B.SilkS")
			(effects
				(font
					(size 1.905 1.4224)
					(thickness 0.1524)
				)
				(justify left mirror)
			)
		)
		(fp_text user "+"
			(at 6.214872 -0.337058 90)
			(unlocked yes)
			(layer "B.Fab")
			(effects
				(font
					(size 1.905 1.4224)
					(thickness 0.1524)
				)
				(justify left mirror)
			)
		)
		(fp_text user "-"
			(at -4.313174 -0.094488 90)
			(unlocked yes)
			(layer "B.Fab")
			(effects
				(font
					(size 1.905 1.4224)
					(thickness 0.1524)
				)
				(justify left mirror)
			)
		)
		(pad "1" smd rect
			(at 3.199892 0 270)
			(size 2.413 2.8194)
			(layers "B.Cu" "B.Mask" "B.Paste")
			(net "P0V9_CPU1_RT_2D")
		)
		(pad "2" smd rect
			(at -3.199892 0 270)
			(size 2.413 2.8194)
			(layers "B.Cu" "B.Mask" "B.Paste")
			(net "GND")
		)
	)
	(footprint ""
		(layer "B.Cu")
		(at 145.197068 -381.50419)
		(property "Reference" "C7028"
			(at 0 0 0)
			(layer "B.SilkS")
			(hide yes)
			(effects
				(font
					(size 1.27 1.27)
				)
				(justify mirror)
			)
		)
		(property "Value" ""
			(at 0 0 0)
			(layer "B.Fab")
			(effects
				(font
					(size 1.27 1.27)
				)
				(justify mirror)
			)
		)
		(duplicate_pad_numbers_are_jumpers no)
		(fp_line
			(start -1.524 -0.762)
			(end -1.524 0.762)
			(stroke
				(width 0.1524)
				(type default)
			)
			(layer "B.SilkS")
		)
		(fp_line
			(start -1.524 0.762)
			(end 1.524 0.762)
			(stroke
				(width 0.1524)
				(type default)
			)
			(layer "B.SilkS")
		)
		(fp_line
			(start 1.524 -0.762)
			(end -1.524 -0.762)
			(stroke
				(width 0.1524)
				(type default)
			)
			(layer "B.SilkS")
		)
		(fp_line
			(start 1.524 0.762)
			(end 1.524 -0.762)
			(stroke
				(width 0.1524)
				(type default)
			)
			(layer "B.SilkS")
		)
		(fp_line
			(start -1.1049 -0.724916)
			(end 1.1049 -0.724916)
			(stroke
				(width 0.1)
				(type default)
			)
			(layer "B.Fab")
		)
		(fp_line
			(start -1.1049 0.724916)
			(end -1.1049 -0.724916)
			(stroke
				(width 0.1)
				(type default)
			)
			(layer "B.Fab")
		)
		(fp_line
			(start 1.1049 -0.724916)
			(end 1.1049 0.724916)
			(stroke
				(width 0.1)
				(type default)
			)
			(layer "B.Fab")
		)
		(fp_line
			(start 1.1049 0.724916)
			(end -1.1049 0.724916)
			(stroke
				(width 0.1)
				(type default)
			)
			(layer "B.Fab")
		)
		(pad "1" smd rect
			(at 0.889 0)
			(size 1.016 1.27)
			(layers "B.Cu" "B.Mask" "B.Paste")
			(net "P0V9_CPU1_RT2_2A")
		)
		(pad "2" smd rect
			(at -0.889 0)
			(size 1.016 1.27)
			(layers "B.Cu" "B.Mask" "B.Paste")
			(net "GND")
		)
	)
)
